# BASEBOARD_FAB2 (Tioga Pass) — schematic netlist excerpt (pin names and nets, part order shuffled) for the footprints in the layout excerpt that follows; sources: Cadence DE-HDL packaged netlist, KiCad conversion of Wiwynn_Tioga_Pass_MB.brd

C2N14  CAP  10UF 6.3V 20% X6S  pkg 0603  page 130 : A = P3V3_STBY ; B = GND
C2U7  CAP  0.22UF 16V 10% X7R  pkg 0402  page 107 : A = P3E_CPU0_PE1_PCH_RXP<2> ; B = P3E_CPU0_PE1_SS_RXP<2>
C2L45  CAP  22UF 6.3V 20% X6S  pkg 0805  page 237 : A = P1V8_PCH_STBY ; B = GND

(kicad_pcb
	(version 20260206)
	(generator "pcbnew")
	(generator_version "10.0")
	(general
		(thickness 1.6)
		(legacy_teardrops no)
	)
	(paper "A4")
	(title_block
		(title "Wiwynn_Tioga_Pass_MB.brd")
		(comment 1 "Tioga Pass / footprints 4188-4190 of 4770")
	)
	(layers
		(0 "F.Cu" signal "TOP")
		(4 "In1.Cu" signal "L2GND")
		(6 "In2.Cu" signal "L3")
		(8 "In3.Cu" signal "L4GND")
		(10 "In4.Cu" signal "L5")
		(12 "In5.Cu" signal "L6GND")
		(14 "In6.Cu" signal "L7VCC")
		(16 "In7.Cu" signal "L8VCC")
		(18 "In8.Cu" signal "L9GND")
		(20 "In9.Cu" signal "L10")
		(22 "In10.Cu" signal "L11GND")
		(24 "In11.Cu" signal "L12")
		(26 "In12.Cu" signal "L13GND")
		(2 "B.Cu" signal "BOTTOM")
		(9 "F.Adhes" user "F.Adhesive")
		(11 "B.Adhes" user "B.Adhesive")
		(13 "F.Paste" user "Package Geometry/Pastemask Top")
		(15 "B.Paste" user "Package Geometry/Pastemask Bottom")
		(5 "F.SilkS" user "Ref Des/Silkscreen Top")
		(7 "B.SilkS" user "Ref Des/Silkscreen Bottom")
		(1 "F.Mask" user "Board Geometry/Soldermask Top")
		(3 "B.Mask" user "Board Geometry/Soldermask Bottom")
		(17 "Dwgs.User" user "User.Drawings")
		(19 "Cmts.User" user "User.Comments")
		(21 "Eco1.User" user "User.Eco1")
		(23 "Eco2.User" user "User.Eco2")
		(25 "Edge.Cuts" user "Board Geometry/Outline")
		(27 "Margin" user)
		(31 "F.CrtYd" user "Package Geometry/Place Bound Top")
		(29 "B.CrtYd" user "Package Geometry/Place Bound Bottom")
		(35 "F.Fab" user "Ref Des/Assembly Top")
		(33 "B.Fab" user "Ref Des/Assembly Bottom")
	)
	(footprint ""
		(layer "B.Cu")
		(at 404.43658 -141.783816 -90)
		(property "Reference" "C2L45"
			(at 0 0 90)
			(layer "B.SilkS")
			(hide yes)
			(effects
				(font
					(size 1.27 1.27)
				)
				(justify mirror)
			)
		)
		(property "Value" ""
			(at 0 0 90)
			(layer "B.Fab")
			(effects
				(font
					(size 1.27 1.27)
				)
				(justify mirror)
			)
		)
		(duplicate_pad_numbers_are_jumpers no)
		(fp_poly
			(pts
				(xy 0.7239 -0.2159) (xy -0.7239 -0.2159) (xy -0.7239 1.9939) (xy 0.7239 1.9939)
			)
			(stroke
				(width 0)
				(type default)
			)
			(fill no)
			(layer "B.CrtYd")
		)
		(fp_line
			(start -0.7239 1.9939)
			(end -0.7239 -0.2159)
			(stroke
				(width 0.1)
				(type default)
			)
			(layer "B.Fab")
		)
		(fp_line
			(start 0.7239 1.9939)
			(end -0.7239 1.9939)
			(stroke
				(width 0.1)
				(type default)
			)
			(layer "B.Fab")
		)
		(fp_line
			(start -0.7239 -0.2159)
			(end 0.7239 -0.2159)
			(stroke
				(width 0.1)
				(type default)
			)
			(layer "B.Fab")
		)
		(fp_line
			(start 0.7239 -0.2159)
			(end 0.7239 1.9939)
			(stroke
				(width 0.1)
				(type default)
			)
			(layer "B.Fab")
		)
		(pad "1" smd rect
			(at 0 0 90)
			(size 1.27 1.016)
			(layers "B.Cu" "B.Mask" "B.Paste")
			(net "P1V8_PCH_STBY")
		)
		(pad "2" smd rect
			(at 0 1.778 90)
			(size 1.27 1.016)
			(layers "B.Cu" "B.Mask" "B.Paste")
			(net "GND")
		)
		(zone
			(layer "B.Cu")
			(hatch none 0.5)
			(connect_pads
				(clearance 0)
			)
			(min_thickness 0.25)
			(keepout
				(tracks not_allowed)
				(vias allowed)
				(pads allowed)
				(copperpour not_allowed)
				(footprints allowed)
			)
			(placement
				(enabled no)
				(sheetname "")
			)
			(fill
				(thermal_gap 0.5)
				(thermal_bridge_width 0.5)
				(island_removal_mode 0)
			)
			(polygon
				(pts
					(xy 403.92858 -141.148816) (xy 403.92858 -142.418816) (xy 403.16658 -142.418816) (xy 403.16658 -141.148816)
				)
			)
		)
	)
	(footprint ""
		(layer "B.Cu")
		(at 401.32 -102.8319)
		(property "Reference" "C2N14"
			(at 0 0 0)
			(layer "B.SilkS")
			(hide yes)
			(effects
				(font
					(size 1.27 1.27)
				)
				(justify mirror)
			)
		)
		(property "Value" ""
			(at 0 0 0)
			(layer "B.Fab")
			(effects
				(font
					(size 1.27 1.27)
				)
				(justify mirror)
			)
		)
		(duplicate_pad_numbers_are_jumpers no)
		(fp_poly
			(pts
				(xy 0.4953 -0.2032) (xy -0.4953 -0.2032) (xy -0.4953 1.6002) (xy 0.4953 1.6002)
			)
			(stroke
				(width 0)
				(type default)
			)
			(fill no)
			(layer "B.CrtYd")
		)
		(fp_line
			(start -0.4953 -0.2032)
			(end -0.4953 1.6002)
			(stroke
				(width 0.1)
				(type default)
			)
			(layer "B.Fab")
		)
		(fp_line
			(start -0.4953 1.6002)
			(end 0.4953 1.6002)
			(stroke
				(width 0.1)
				(type default)
			)
			(layer "B.Fab")
		)
		(fp_line
			(start 0.4953 -0.2032)
			(end -0.4953 -0.2032)
			(stroke
				(width 0.1)
				(type default)
			)
			(layer "B.Fab")
		)
		(fp_line
			(start 0.4953 1.6002)
			(end 0.4953 -0.2032)
			(stroke
				(width 0.1)
				(type default)
			)
			(layer "B.Fab")
		)
		(pad "1" smd rect
			(at 0 0 180)
			(size 0.762 0.889)
			(layers "B.Cu" "B.Mask" "B.Paste")
			(net "P3V3_STBY")
		)
		(pad "2" smd rect
			(at 0 1.397 180)
			(size 0.762 0.889)
			(layers "B.Cu" "B.Mask" "B.Paste")
			(net "GND")
		)
		(zone
			(layer "B.Cu")
			(hatch none 0.5)
			(connect_pads
				(clearance 0)
			)
			(min_thickness 0.25)
			(keepout
				(tracks not_allowed)
				(vias allowed)
				(pads allowed)
				(copperpour not_allowed)
				(footprints allowed)
			)
			(placement
				(enabled no)
				(sheetname "")
			)
			(fill
				(thermal_gap 0.5)
				(thermal_bridge_width 0.5)
				(island_removal_mode 0)
			)
			(polygon
				(pts
					(xy 401.701 -102.3874) (xy 400.939 -102.3874) (xy 400.939 -101.8794) (xy 401.701 -101.8794)
				)
			)
		)
	)
	(footprint ""
		(layer "B.Cu")
		(at 338.934806 -61.257434)
		(property "Reference" "C2U7"
			(at 0 0 0)
			(layer "B.SilkS")
			(hide yes)
			(effects
				(font
					(size 1.27 1.27)
				)
				(justify mirror)
			)
		)
		(property "Value" ""
			(at 0 0 0)
			(layer "B.Fab")
			(effects
				(font
					(size 1.27 1.27)
				)
				(justify mirror)
			)
		)
		(duplicate_pad_numbers_are_jumpers no)
		(fp_poly
			(pts
				(xy -0.3048 -0.1016) (xy -0.3048 0.9906) (xy 0.3048 0.9906) (xy 0.3048 -0.1016)
			)
			(stroke
				(width 0)
				(type default)
			)
			(fill no)
			(layer "B.CrtYd")
		)
		(fp_line
			(start -0.3048 -0.1016)
			(end 0.3048 -0.1016)
			(stroke
				(width 0.1)
				(type default)
			)
			(layer "B.Fab")
		)
		(fp_line
			(start -0.3048 0.9906)
			(end -0.3048 -0.1016)
			(stroke
				(width 0.1)
				(type default)
			)
			(layer "B.Fab")
		)
		(fp_line
			(start 0.3048 -0.1016)
			(end 0.3048 0.9906)
			(stroke
				(width 0.1)
				(type default)
			)
			(layer "B.Fab")
		)
		(fp_line
			(start 0.3048 0.9906)
			(end -0.3048 0.9906)
			(stroke
				(width 0.1)
				(type default)
			)
			(layer "B.Fab")
		)
		(pad "1" smd rect
			(at 0 0 180)
			(size 0.508 0.508)
			(layers "B.Cu" "B.Mask" "B.Paste")
			(net "P3E_CPU0_PE1_PCH_RXP<2>")
		)
		(pad "2" smd rect
			(at 0 0.889 180)
			(size 0.508 0.508)
			(layers "B.Cu" "B.Mask" "B.Paste")
			(net "P3E_CPU0_PE1_SS_RXP<2>")
		)
		(zone
			(layer "B.Cu")
			(hatch none 0.5)
			(connect_pads
				(clearance 0)
			)
			(min_thickness 0.25)
			(keepout
				(tracks allowed)
				(vias not_allowed)
				(pads allowed)
				(copperpour not_allowed)
				(footprints allowed)
			)
			(placement
				(enabled no)
				(sheetname "")
			)
			(fill
				(thermal_gap 0.5)
				(thermal_bridge_width 0.5)
				(island_removal_mode 0)
			)
			(polygon
				(pts
					(xy 339.188806 -61.003434) (xy 338.680806 -61.003434) (xy 338.680806 -60.622434) (xy 339.188806 -60.622434)
				)
			)
		)
		(zone
			(layer "B.Cu")
			(hatch none 0.5)
			(connect_pads
				(clearance 0)
			)
			(min_thickness 0.25)
			(keepout
				(tracks not_allowed)
				(vias allowed)
				(pads allowed)
				(copperpour not_allowed)
				(footprints allowed)
			)
			(placement
				(enabled no)
				(sheetname "")
			)
			(fill
				(thermal_gap 0.5)
				(thermal_bridge_width 0.5)
				(island_removal_mode 0)
			)
			(polygon
				(pts
					(xy 339.188806 -60.622434) (xy 338.680806 -60.622434) (xy 338.680806 -61.003434) (xy 339.188806 -61.003434)
				)
			)
		)
	)
)
